# T6G (Grand Teton) — schematic netlist excerpt (pin names and nets, part order shuffled) for the footprints in the layout excerpt that follows; sources: Cadence DE-HDL packaged netlist, KiCad conversion of 04192023_DAF0TMB3IC0_F0TG_MB_C_brd_V02_OCP.brd

R3443  Q_RES  0 5% CHIP  pkg 0402LF  page 123 : A = GPU_PEX_STRAP1 ; B = GND
PC520  Q_CAP  0.22UF 16V 10% X7R  pkg 0402  page 225 : A = SW_PVDD11_S3_P1_BOOT2_RC ; B = SW_PVDD11_S3_P1_PH2

(kicad_pcb
	(version 20260206)
	(generator "pcbnew")
	(generator_version "10.0")
	(general
		(thickness 1.6)
		(legacy_teardrops no)
	)
	(paper "A4")
	(title_block
		(title "04192023_DAF0TMB3IC0_F0TG_MB_C_brd_V02_OCP.brd")
		(comment 1 "Grand Teton / footprints 4767-4768 of 8354")
	)
	(layers
		(0 "F.Cu" signal "TOP")
		(4 "In1.Cu" signal "GND")
		(6 "In2.Cu" signal "IN1")
		(8 "In3.Cu" signal "GND1")
		(10 "In4.Cu" signal "IN2")
		(12 "In5.Cu" signal "GND2")
		(14 "In6.Cu" signal "IN3")
		(16 "In7.Cu" signal "GND3")
		(18 "In8.Cu" signal "VCC")
		(20 "In9.Cu" signal "VCC1")
		(22 "In10.Cu" signal "GND4")
		(24 "In11.Cu" signal "IN4")
		(26 "In12.Cu" signal "GND5")
		(28 "In13.Cu" signal "IN5")
		(30 "In14.Cu" signal "GND6")
		(32 "In15.Cu" signal "IN6")
		(34 "In16.Cu" signal "GND7")
		(2 "B.Cu" signal "BOTTOM")
		(9 "F.Adhes" user "F.Adhesive")
		(11 "B.Adhes" user "B.Adhesive")
		(13 "F.Paste" user "Package Geometry/Pastemask Top")
		(15 "B.Paste" user "Package Geometry/Pastemask Bottom")
		(5 "F.SilkS" user "Ref Des/Silkscreen Top")
		(7 "B.SilkS" user "Ref Des/Silkscreen Bottom")
		(1 "F.Mask" user "Board Geometry/Soldermask Top")
		(3 "B.Mask" user "Board Geometry/Soldermask Bottom")
		(17 "Dwgs.User" user "User.Drawings")
		(19 "Cmts.User" user "User.Comments")
		(21 "Eco1.User" user "User.Eco1")
		(23 "Eco2.User" user "User.Eco2")
		(25 "Edge.Cuts" user "Board Geometry/Outline")
		(27 "Margin" user)
		(31 "F.CrtYd" user "Package Geometry/Place Bound Top")
		(29 "B.CrtYd" user "Package Geometry/Place Bound Bottom")
		(35 "F.Fab" user "Ref Des/Assembly Top")
		(33 "B.Fab" user "Ref Des/Assembly Bottom")
	)
	(footprint ""
		(layer "F.Cu")
		(at 193.03238 -355.924358 -90)
		(property "Reference" "PC520"
			(at 0 0 270)
			(layer "F.SilkS")
			(hide yes)
			(effects
				(font
					(size 1.27 1.27)
				)
			)
		)
		(property "Value" ""
			(at 0 0 270)
			(layer "F.Fab")
			(effects
				(font
					(size 1.27 1.27)
				)
			)
		)
		(duplicate_pad_numbers_are_jumpers no)
		(fp_line
			(start -0.7874 0.4064)
			(end -0.7874 -0.4064)
			(stroke
				(width 0.1524)
				(type default)
			)
			(layer "F.SilkS")
		)
		(fp_line
			(start 0.7874 0.4064)
			(end -0.7874 0.4064)
			(stroke
				(width 0.1524)
				(type default)
			)
			(layer "F.SilkS")
		)
		(fp_line
			(start -0.7874 -0.4064)
			(end 0.7874 -0.4064)
			(stroke
				(width 0.1524)
				(type default)
			)
			(layer "F.SilkS")
		)
		(fp_line
			(start 0.7874 -0.4064)
			(end 0.7874 0.4064)
			(stroke
				(width 0.1524)
				(type default)
			)
			(layer "F.SilkS")
		)
		(fp_line
			(start -0.67945 0.3048)
			(end -0.67945 -0.305054)
			(stroke
				(width 0.1)
				(type default)
			)
			(layer "F.Fab")
		)
		(fp_line
			(start -0.12065 0.3048)
			(end -0.67945 0.3048)
			(stroke
				(width 0.1)
				(type default)
			)
			(layer "F.Fab")
		)
		(fp_line
			(start 0.120396 0.3048)
			(end 0.120396 0.2794)
			(stroke
				(width 0.1)
				(type default)
			)
			(layer "F.Fab")
		)
		(fp_line
			(start 0.67945 0.3048)
			(end 0.120396 0.3048)
			(stroke
				(width 0.1)
				(type default)
			)
			(layer "F.Fab")
		)
		(fp_line
			(start -0.12065 0.2794)
			(end -0.12065 0.3048)
			(stroke
				(width 0.1)
				(type default)
			)
			(layer "F.Fab")
		)
		(fp_line
			(start 0.120396 0.2794)
			(end -0.12065 0.2794)
			(stroke
				(width 0.1)
				(type default)
			)
			(layer "F.Fab")
		)
		(fp_line
			(start -0.12065 -0.2794)
			(end 0.12065 -0.2794)
			(stroke
				(width 0.1)
				(type default)
			)
			(layer "F.Fab")
		)
		(fp_line
			(start 0.12065 -0.2794)
			(end 0.12065 -0.3048)
			(stroke
				(width 0.1)
				(type default)
			)
			(layer "F.Fab")
		)
		(fp_line
			(start 0.12065 -0.3048)
			(end 0.67945 -0.3048)
			(stroke
				(width 0.1)
				(type default)
			)
			(layer "F.Fab")
		)
		(fp_line
			(start 0.67945 -0.3048)
			(end 0.67945 0.3048)
			(stroke
				(width 0.1)
				(type default)
			)
			(layer "F.Fab")
		)
		(fp_line
			(start -0.67945 -0.305054)
			(end -0.12065 -0.305054)
			(stroke
				(width 0.1)
				(type default)
			)
			(layer "F.Fab")
		)
		(fp_line
			(start -0.12065 -0.305054)
			(end -0.12065 -0.2794)
			(stroke
				(width 0.1)
				(type default)
			)
			(layer "F.Fab")
		)
		(pad "1" smd circle
			(at -0.40005 0 270)
			(size 0 0)
			(layers "F.Cu" "F.Mask" "F.Paste")
			(net "SW_PVDD11_S3_P1_BOOT2_RC")
		)
		(pad "2" smd circle
			(at 0.40005 0 270)
			(size 0 0)
			(layers "F.Cu" "F.Mask" "F.Paste")
			(net "SW_PVDD11_S3_P1_PH2")
		)
	)
	(footprint ""
		(layer "F.Cu")
		(at 185.027316 -428.372016 90)
		(property "Reference" "R3443"
			(at 0 0 90)
			(layer "F.SilkS")
			(hide yes)
			(effects
				(font
					(size 1.27 1.27)
				)
			)
		)
		(property "Value" ""
			(at 0 0 90)
			(layer "F.Fab")
			(effects
				(font
					(size 1.27 1.27)
				)
			)
		)
		(duplicate_pad_numbers_are_jumpers no)
		(fp_line
			(start 0.7874 -0.4064)
			(end 0.7874 0.4064)
			(stroke
				(width 0.1524)
				(type default)
			)
			(layer "F.SilkS")
		)
		(fp_line
			(start -0.7874 -0.4064)
			(end 0.7874 -0.4064)
			(stroke
				(width 0.1524)
				(type default)
			)
			(layer "F.SilkS")
		)
		(fp_line
			(start 0.7874 0.4064)
			(end -0.7874 0.4064)
			(stroke
				(width 0.1524)
				(type default)
			)
			(layer "F.SilkS")
		)
		(fp_line
			(start -0.7874 0.4064)
			(end -0.7874 -0.4064)
			(stroke
				(width 0.1524)
				(type default)
			)
			(layer "F.SilkS")
		)
		(fp_line
			(start -0.12065 -0.305054)
			(end -0.12065 -0.2794)
			(stroke
				(width 0.1)
				(type default)
			)
			(layer "F.Fab")
		)
		(fp_line
			(start -0.67945 -0.305054)
			(end -0.12065 -0.305054)
			(stroke
				(width 0.1)
				(type default)
			)
			(layer "F.Fab")
		)
		(fp_line
			(start 0.67945 -0.3048)
			(end 0.67945 0.3048)
			(stroke
				(width 0.1)
				(type default)
			)
			(layer "F.Fab")
		)
		(fp_line
			(start 0.12065 -0.3048)
			(end 0.67945 -0.3048)
			(stroke
				(width 0.1)
				(type default)
			)
			(layer "F.Fab")
		)
		(fp_line
			(start 0.12065 -0.2794)
			(end 0.12065 -0.3048)
			(stroke
				(width 0.1)
				(type default)
			)
			(layer "F.Fab")
		)
		(fp_line
			(start -0.12065 -0.2794)
			(end 0.12065 -0.2794)
			(stroke
				(width 0.1)
				(type default)
			)
			(layer "F.Fab")
		)
		(fp_line
			(start 0.120396 0.2794)
			(end -0.12065 0.2794)
			(stroke
				(width 0.1)
				(type default)
			)
			(layer "F.Fab")
		)
		(fp_line
			(start -0.12065 0.2794)
			(end -0.12065 0.3048)
			(stroke
				(width 0.1)
				(type default)
			)
			(layer "F.Fab")
		)
		(fp_line
			(start 0.67945 0.3048)
			(end 0.120396 0.3048)
			(stroke
				(width 0.1)
				(type default)
			)
			(layer "F.Fab")
		)
		(fp_line
			(start 0.120396 0.3048)
			(end 0.120396 0.2794)
			(stroke
				(width 0.1)
				(type default)
			)
			(layer "F.Fab")
		)
		(fp_line
			(start -0.12065 0.3048)
			(end -0.67945 0.3048)
			(stroke
				(width 0.1)
				(type default)
			)
			(layer "F.Fab")
		)
		(fp_line
			(start -0.67945 0.3048)
			(end -0.67945 -0.305054)
			(stroke
				(width 0.1)
				(type default)
			)
			(layer "F.Fab")
		)
		(pad "1" smd circle
			(at -0.40005 0 90)
			(size 0 0)
			(layers "F.Cu" "F.Mask" "F.Paste")
			(net "GPU_PEX_STRAP1")
		)
		(pad "2" smd circle
			(at 0.40005 0 90)
			(size 0 0)
			(layers "F.Cu" "F.Mask" "F.Paste")
			(net "GND")
		)
	)
)
